# T6G (Grand Teton) — schematic netlist excerpt (pin names and nets, part order shuffled) for the footprints in the layout excerpt that follows; sources: Cadence DE-HDL packaged netlist, KiCad conversion of 04192023_DAF0TMB3IC0_F0TG_MB_C_brd_V02_OCP.brd

X8003  TP_TDR_4P_FTS  TP_TDR_4P_DIP EMPTY  pkg TH  page 260
  S1  = TDR_DIFF_85_IN2_DP
  P1  = T1_GND
  P2  = T1_GND
  S2  = TDR_DIFF_85_IN2_DN

PC81_C1P0_1  Q_CAP  2.2UF 10V 10% X6S  pkg C0402  page 201 : A = PVDDCR_CPU1_P0_PVCC ; B = GND

(kicad_pcb
	(version 20260206)
	(generator "pcbnew")
	(generator_version "10.0")
	(general
		(thickness 1.6)
		(legacy_teardrops no)
	)
	(paper "A4")
	(title_block
		(title "04192023_DAF0TMB3IC0_F0TG_MB_C_brd_V02_OCP.brd")
		(comment 1 "Grand Teton / footprints 4081-4083 of 8354")
	)
	(layers
		(0 "F.Cu" signal "TOP")
		(4 "In1.Cu" signal "GND")
		(6 "In2.Cu" signal "IN1")
		(8 "In3.Cu" signal "GND1")
		(10 "In4.Cu" signal "IN2")
		(12 "In5.Cu" signal "GND2")
		(14 "In6.Cu" signal "IN3")
		(16 "In7.Cu" signal "GND3")
		(18 "In8.Cu" signal "VCC")
		(20 "In9.Cu" signal "VCC1")
		(22 "In10.Cu" signal "GND4")
		(24 "In11.Cu" signal "IN4")
		(26 "In12.Cu" signal "GND5")
		(28 "In13.Cu" signal "IN5")
		(30 "In14.Cu" signal "GND6")
		(32 "In15.Cu" signal "IN6")
		(34 "In16.Cu" signal "GND7")
		(2 "B.Cu" signal "BOTTOM")
		(9 "F.Adhes" user "F.Adhesive")
		(11 "B.Adhes" user "B.Adhesive")
		(13 "F.Paste" user "Package Geometry/Pastemask Top")
		(15 "B.Paste" user "Package Geometry/Pastemask Bottom")
		(5 "F.SilkS" user "Ref Des/Silkscreen Top")
		(7 "B.SilkS" user "Ref Des/Silkscreen Bottom")
		(1 "F.Mask" user "Board Geometry/Soldermask Top")
		(3 "B.Mask" user "Board Geometry/Soldermask Bottom")
		(17 "Dwgs.User" user "User.Drawings")
		(19 "Cmts.User" user "User.Comments")
		(21 "Eco1.User" user "User.Eco1")
		(23 "Eco2.User" user "User.Eco2")
		(25 "Edge.Cuts" user "Board Geometry/Outline")
		(27 "Margin" user)
		(31 "F.CrtYd" user "Package Geometry/Place Bound Top")
		(29 "B.CrtYd" user "Package Geometry/Place Bound Bottom")
		(35 "F.Fab" user "Ref Des/Assembly Top")
		(33 "B.Fab" user "Ref Des/Assembly Bottom")
	)
	(footprint ""
		(layer "F.Cu")
		(at 331.37602 -334.971898 -90)
		(property "Reference" "PC81_C1P0_1"
			(at 0 0 270)
			(layer "F.SilkS")
			(hide yes)
			(effects
				(font
					(size 1.27 1.27)
				)
			)
		)
		(property "Value" ""
			(at 0 0 270)
			(layer "F.Fab")
			(effects
				(font
					(size 1.27 1.27)
				)
			)
		)
		(duplicate_pad_numbers_are_jumpers no)
		(fp_line
			(start -0.7874 0.4064)
			(end -0.7874 -0.4064)
			(stroke
				(width 0.1524)
				(type default)
			)
			(layer "F.SilkS")
		)
		(fp_line
			(start 0.7874 0.4064)
			(end -0.7874 0.4064)
			(stroke
				(width 0.1524)
				(type default)
			)
			(layer "F.SilkS")
		)
		(fp_line
			(start -0.7874 -0.4064)
			(end 0.7874 -0.4064)
			(stroke
				(width 0.1524)
				(type default)
			)
			(layer "F.SilkS")
		)
		(fp_line
			(start 0.7874 -0.4064)
			(end 0.7874 0.4064)
			(stroke
				(width 0.1524)
				(type default)
			)
			(layer "F.SilkS")
		)
		(fp_line
			(start -0.67945 0.3048)
			(end -0.67945 -0.305054)
			(stroke
				(width 0.1)
				(type default)
			)
			(layer "F.Fab")
		)
		(fp_line
			(start -0.12065 0.3048)
			(end -0.67945 0.3048)
			(stroke
				(width 0.1)
				(type default)
			)
			(layer "F.Fab")
		)
		(fp_line
			(start 0.120396 0.3048)
			(end 0.120396 0.2794)
			(stroke
				(width 0.1)
				(type default)
			)
			(layer "F.Fab")
		)
		(fp_line
			(start 0.67945 0.3048)
			(end 0.120396 0.3048)
			(stroke
				(width 0.1)
				(type default)
			)
			(layer "F.Fab")
		)
		(fp_line
			(start -0.12065 0.2794)
			(end -0.12065 0.3048)
			(stroke
				(width 0.1)
				(type default)
			)
			(layer "F.Fab")
		)
		(fp_line
			(start 0.120396 0.2794)
			(end -0.12065 0.2794)
			(stroke
				(width 0.1)
				(type default)
			)
			(layer "F.Fab")
		)
		(fp_line
			(start -0.12065 -0.2794)
			(end 0.12065 -0.2794)
			(stroke
				(width 0.1)
				(type default)
			)
			(layer "F.Fab")
		)
		(fp_line
			(start 0.12065 -0.2794)
			(end 0.12065 -0.3048)
			(stroke
				(width 0.1)
				(type default)
			)
			(layer "F.Fab")
		)
		(fp_line
			(start 0.12065 -0.3048)
			(end 0.67945 -0.3048)
			(stroke
				(width 0.1)
				(type default)
			)
			(layer "F.Fab")
		)
		(fp_line
			(start 0.67945 -0.3048)
			(end 0.67945 0.3048)
			(stroke
				(width 0.1)
				(type default)
			)
			(layer "F.Fab")
		)
		(fp_line
			(start -0.67945 -0.305054)
			(end -0.12065 -0.305054)
			(stroke
				(width 0.1)
				(type default)
			)
			(layer "F.Fab")
		)
		(fp_line
			(start -0.12065 -0.305054)
			(end -0.12065 -0.2794)
			(stroke
				(width 0.1)
				(type default)
			)
			(layer "F.Fab")
		)
		(pad "1" smd circle
			(at -0.40005 0 270)
			(size 0 0)
			(layers "F.Cu" "F.Mask" "F.Paste")
			(net "PVDDCR_CPU1_P0_PVCC")
		)
		(pad "2" smd circle
			(at 0.40005 0 270)
			(size 0 0)
			(layers "F.Cu" "F.Mask" "F.Paste")
			(net "GND")
		)
	)
	(footprint ""
		(layer "F.Cu")
		(at 316.15761 137.70356 90)
		(property "Reference" "ME5"
			(at 0.0254 -3.851148 90)
			(unlocked yes)
			(layer "F.SilkS")
			(effects
				(font
					(size 0.7874 0.5842)
					(thickness 0.1524)
				)
				(justify left)
			)
		)
		(property "Value" ""
			(at 0 0 90)
			(layer "F.Fab")
			(effects
				(font
					(size 1.27 1.27)
				)
			)
		)
		(duplicate_pad_numbers_are_jumpers no)
	)
	(footprint ""
		(layer "F.Cu")
		(at 498.693948 -142.844266 90)
		(property "Reference" "X8003"
			(at -1.975358 1.637792 0)
			(unlocked yes)
			(layer "F.SilkS")
			(effects
				(font
					(size 0.7874 0.5842)
					(thickness 0.1524)
				)
				(justify left)
			)
		)
		(property "Value" ""
			(at 0 0 90)
			(layer "F.Fab")
			(effects
				(font
					(size 1.27 1.27)
				)
			)
		)
		(property "Device Type" "TP_TDR_4P_FTS_TH-TP_TDR_4P_DIP,EMPTY,TP15"
			(at 1.30175 1.27 180)
			(unlocked yes)
			(layer "F.Fab")
			(hide yes)
			(effects
				(font
					(size 0.635 0.4064)
					(thickness 0.1524)
				)
			)
		)
		(property "User Part Number" "N_A"
			(at 1.30175 1.27 180)
			(unlocked yes)
			(layer "Cmts.User")
			(hide yes)
			(effects
				(font
					(size 0.635 0.4064)
					(thickness 0.1524)
				)
			)
		)
		(duplicate_pad_numbers_are_jumpers no)
		(fp_line
			(start 2.54 -1.27)
			(end 0 -1.27)
			(stroke
				(width 0.1524)
				(type default)
			)
			(layer "F.SilkS")
		)
		(fp_line
			(start 0 -1.27)
			(end 0 -0.635)
			(stroke
				(width 0.1524)
				(type default)
			)
			(layer "F.SilkS")
		)
		(fp_line
			(start 2.54 -1.1303)
			(end 2.54 -1.27)
			(stroke
				(width 0.1524)
				(type default)
			)
			(layer "F.SilkS")
		)
		(fp_line
			(start 0 0.635)
			(end 0 1.905)
			(stroke
				(width 0.1524)
				(type default)
			)
			(layer "F.SilkS")
		)
		(fp_line
			(start 2.54 1.4097)
			(end 2.54 1.1303)
			(stroke
				(width 0.1524)
				(type default)
			)
			(layer "F.SilkS")
		)
		(fp_line
			(start 0 3.175)
			(end 0 3.81)
			(stroke
				(width 0.1524)
				(type default)
			)
			(layer "F.SilkS")
		)
		(fp_line
			(start 2.54 3.81)
			(end 2.54 3.6703)
			(stroke
				(width 0.1524)
				(type default)
			)
			(layer "F.SilkS")
		)
		(fp_line
			(start 0 3.81)
			(end 2.54 3.81)
			(stroke
				(width 0.1524)
				(type default)
			)
			(layer "F.SilkS")
		)
		(fp_poly
			(pts
				(xy -2.285746 -0.762) (xy -0.761746 0) (xy -2.285746 0.762)
			)
			(stroke
				(width 0)
				(type default)
			)
			(fill yes)
			(layer "F.SilkS")
		)
		(fp_line
			(start 2.54 -1.27)
			(end 0 -1.27)
			(stroke
				(width 0.1)
				(type default)
			)
			(layer "F.Fab")
		)
		(fp_line
			(start 0 -1.27)
			(end 0 3.81)
			(stroke
				(width 0.1)
				(type default)
			)
			(layer "F.Fab")
		)
		(fp_line
			(start 2.54 3.81)
			(end 2.54 -1.27)
			(stroke
				(width 0.1)
				(type default)
			)
			(layer "F.Fab")
		)
		(fp_line
			(start 0 3.81)
			(end 2.54 3.81)
			(stroke
				(width 0.1)
				(type default)
			)
			(layer "F.Fab")
		)
		(fp_poly
			(pts
				(xy -0.761746 0) (xy -2.285746 -0.762) (xy -2.285746 0.762)
			)
			(stroke
				(width 0)
				(type default)
			)
			(fill yes)
			(layer "F.Fab")
		)
		(pad "1" thru_hole circle
			(at 0 0 90)
			(size 1.0033 1.0033)
			(drill 0.249936)
			(layers "*.Cu" "*.Mask")
			(remove_unused_layers no)
			(net "TDR_DIFF_85_IN2_DP")
			(clearance 0.10795)
			(thermal_gap 0.10795)
			(padstack
				(mode front_inner_back)
				(layer "Inner"
					(shape circle)
					(size 0.8001 0.8001)
					(clearance 0.1524)
				)
				(layer "B.Cu"
					(shape circle)
					(size 1.0033 1.0033)
					(clearance 0.10795)
				)
			)
		)
		(pad "2" thru_hole circle
			(at 2.54 0 90)
			(size 1.9939 1.9939)
			(drill 0.249936)
			(layers "*.Cu" "*.Mask")
			(remove_unused_layers no)
			(net "T1_GND")
			(clearance 0.10795)
			(thermal_gap 0.10795)
			(padstack
				(mode front_inner_back)
				(layer "Inner"
					(shape circle)
					(size 0.8001 0.8001)
					(clearance 0.1524)
				)
				(layer "B.Cu"
					(shape circle)
					(size 1.9939 1.9939)
					(clearance 0.10795)
				)
			)
		)
		(pad "3" thru_hole circle
			(at 2.54 2.54 90)
			(size 1.9939 1.9939)
			(drill 0.249936)
			(layers "*.Cu" "*.Mask")
			(remove_unused_layers no)
			(net "T1_GND")
			(clearance 0.10795)
			(thermal_gap 0.10795)
			(padstack
				(mode front_inner_back)
				(layer "Inner"
					(shape circle)
					(size 0.8001 0.8001)
					(clearance 0.1524)
				)
				(layer "B.Cu"
					(shape circle)
					(size 1.9939 1.9939)
					(clearance 0.10795)
				)
			)
		)
		(pad "4" thru_hole circle
			(at 0 2.54 90)
			(size 1.0033 1.0033)
			(drill 0.249936)
			(layers "*.Cu" "*.Mask")
			(remove_unused_layers no)
			(net "TDR_DIFF_85_IN2_DN")
			(clearance 0.10795)
			(thermal_gap 0.10795)
			(padstack
				(mode front_inner_back)
				(layer "Inner"
					(shape circle)
					(size 0.8001 0.8001)
					(clearance 0.1524)
				)
				(layer "B.Cu"
					(shape circle)
					(size 1.0033 1.0033)
					(clearance 0.10795)
				)
			)
		)
	)
)
